(kicad_pcb
	(version 20260206)
	(generator "pcbnew")
	(generator_version "10.0")
	(general
		(thickness 1.6)
		(legacy_teardrops no)
	)
	(paper "A4")
	(title_block
		(title "01162023_DA0F0TEBIF0_F0T_Expander_BD_F_brd_V02_OCP.brd")
		(comment 1 "Grand Teton / footprints 617-623 of 9728")
	)
	(layers
		(0 "F.Cu" signal "TOP")
		(4 "In1.Cu" signal "GND")
		(6 "In2.Cu" signal "VCC")
		(8 "In3.Cu" signal "VCC1")
		(10 "In4.Cu" signal "GND1")
		(12 "In5.Cu" signal "IN1")
		(14 "In6.Cu" signal "GND2")
		(16 "In7.Cu" signal "IN2")
		(18 "In8.Cu" signal "GND3")
		(20 "In9.Cu" signal "IN3")
		(22 "In10.Cu" signal "GND4")
		(24 "In11.Cu" signal "IN4")
		(26 "In12.Cu" signal "GND5")
		(28 "In13.Cu" signal "IN5")
		(30 "In14.Cu" signal "GND6")
		(32 "In15.Cu" signal "IN6")
		(34 "In16.Cu" signal "GND7")
		(2 "B.Cu" signal "BOTTOM")
		(9 "F.Adhes" user "F.Adhesive")
		(11 "B.Adhes" user "B.Adhesive")
		(13 "F.Paste" user "Package Geometry/Pastemask Top")
		(15 "B.Paste" user "Package Geometry/Pastemask Bottom")
		(5 "F.SilkS" user "Ref Des/Silkscreen Top")
		(7 "B.SilkS" user "Ref Des/Silkscreen Bottom")
		(1 "F.Mask" user "Board Geometry/Soldermask Top")
		(3 "B.Mask" user "Board Geometry/Soldermask Bottom")
		(17 "Dwgs.User" user "User.Drawings")
		(19 "Cmts.User" user "User.Comments")
		(21 "Eco1.User" user "User.Eco1")
		(23 "Eco2.User" user "User.Eco2")
		(25 "Edge.Cuts" user "Board Geometry/Outline")
		(27 "Margin" user)
		(31 "F.CrtYd" user "Package Geometry/Place Bound Top")
		(29 "B.CrtYd" user "Package Geometry/Place Bound Bottom")
		(35 "F.Fab" user "Ref Des/Assembly Top")
		(33 "B.Fab" user "Ref Des/Assembly Bottom")
	)
	(footprint ""
		(layer "F.Cu")
		(at 107.051094 -397.512286 -90)
		(property "Reference" "R6181"
			(at 0 0 270)
			(layer "F.SilkS")
			(hide yes)
			(effects
				(font
					(size 1.27 1.27)
				)
			)
		)
		(property "Value" ""
			(at 0 0 270)
			(layer "F.Fab")
			(effects
				(font
					(size 1.27 1.27)
				)
			)
		)
		(duplicate_pad_numbers_are_jumpers no)
		(fp_line
			(start -0.7874 0.4064)
			(end -0.7874 -0.4064)
			(stroke
				(width 0.1524)
				(type default)
			)
			(layer "F.SilkS")
		)
		(fp_line
			(start 0.7874 0.4064)
			(end -0.7874 0.4064)
			(stroke
				(width 0.1524)
				(type default)
			)
			(layer "F.SilkS")
		)
		(fp_line
			(start -0.7874 -0.4064)
			(end 0.7874 -0.4064)
			(stroke
				(width 0.1524)
				(type default)
			)
			(layer "F.SilkS")
		)
		(fp_line
			(start 0.7874 -0.4064)
			(end 0.7874 0.4064)
			(stroke
				(width 0.1524)
				(type default)
			)
			(layer "F.SilkS")
		)
		(fp_line
			(start -0.67945 0.3048)
			(end -0.67945 -0.305054)
			(stroke
				(width 0.1)
				(type default)
			)
			(layer "F.Fab")
		)
		(fp_line
			(start -0.12065 0.3048)
			(end -0.67945 0.3048)
			(stroke
				(width 0.1)
				(type default)
			)
			(layer "F.Fab")
		)
		(fp_line
			(start 0.120396 0.3048)
			(end 0.120396 0.2794)
			(stroke
				(width 0.1)
				(type default)
			)
			(layer "F.Fab")
		)
		(fp_line
			(start 0.67945 0.3048)
			(end 0.120396 0.3048)
			(stroke
				(width 0.1)
				(type default)
			)
			(layer "F.Fab")
		)
		(fp_line
			(start -0.12065 0.2794)
			(end -0.12065 0.3048)
			(stroke
				(width 0.1)
				(type default)
			)
			(layer "F.Fab")
		)
		(fp_line
			(start 0.120396 0.2794)
			(end -0.12065 0.2794)
			(stroke
				(width 0.1)
				(type default)
			)
			(layer "F.Fab")
		)
		(fp_line
			(start -0.12065 -0.2794)
			(end 0.12065 -0.2794)
			(stroke
				(width 0.1)
				(type default)
			)
			(layer "F.Fab")
		)
		(fp_line
			(start 0.12065 -0.2794)
			(end 0.12065 -0.3048)
			(stroke
				(width 0.1)
				(type default)
			)
			(layer "F.Fab")
		)
		(fp_line
			(start 0.12065 -0.3048)
			(end 0.67945 -0.3048)
			(stroke
				(width 0.1)
				(type default)
			)
			(layer "F.Fab")
		)
		(fp_line
			(start 0.67945 -0.3048)
			(end 0.67945 0.3048)
			(stroke
				(width 0.1)
				(type default)
			)
			(layer "F.Fab")
		)
		(fp_line
			(start -0.67945 -0.305054)
			(end -0.12065 -0.305054)
			(stroke
				(width 0.1)
				(type default)
			)
			(layer "F.Fab")
		)
		(fp_line
			(start -0.12065 -0.305054)
			(end -0.12065 -0.2794)
			(stroke
				(width 0.1)
				(type default)
			)
			(layer "F.Fab")
		)
		(pad "1" smd circle
			(at -0.40005 0 270)
			(size 0 0)
			(layers "F.Cu" "F.Mask" "F.Paste")
			(net "RST_BIC_USB_HUB_R_N")
		)
		(pad "2" smd circle
			(at 0.40005 0 270)
			(size 0 0)
			(layers "F.Cu" "F.Mask" "F.Paste")
			(net "RST_BIC_USB_HUB_R1_N")
		)
	)
	(footprint ""
		(layer "F.Cu")
		(at 381.254 -198.374)
		(property "Reference" "R4696"
			(at 0 0 0)
			(layer "F.SilkS")
			(hide yes)
			(effects
				(font
					(size 1.27 1.27)
				)
			)
		)
		(property "Value" ""
			(at 0 0 0)
			(layer "F.Fab")
			(effects
				(font
					(size 1.27 1.27)
				)
			)
		)
		(duplicate_pad_numbers_are_jumpers no)
		(fp_line
			(start -0.7874 -0.4064)
			(end 0.7874 -0.4064)
			(stroke
				(width 0.1524)
				(type default)
			)
			(layer "F.SilkS")
		)
		(fp_line
			(start -0.7874 0.4064)
			(end -0.7874 -0.4064)
			(stroke
				(width 0.1524)
				(type default)
			)
			(layer "F.SilkS")
		)
		(fp_line
			(start 0.7874 -0.4064)
			(end 0.7874 0.4064)
			(stroke
				(width 0.1524)
				(type default)
			)
			(layer "F.SilkS")
		)
		(fp_line
			(start 0.7874 0.4064)
			(end -0.7874 0.4064)
			(stroke
				(width 0.1524)
				(type default)
			)
			(layer "F.SilkS")
		)
		(fp_line
			(start -0.67945 -0.305054)
			(end -0.12065 -0.305054)
			(stroke
				(width 0.1)
				(type default)
			)
			(layer "F.Fab")
		)
		(fp_line
			(start -0.67945 0.3048)
			(end -0.67945 -0.305054)
			(stroke
				(width 0.1)
				(type default)
			)
			(layer "F.Fab")
		)
		(fp_line
			(start -0.12065 -0.305054)
			(end -0.12065 -0.2794)
			(stroke
				(width 0.1)
				(type default)
			)
			(layer "F.Fab")
		)
		(fp_line
			(start -0.12065 -0.2794)
			(end 0.12065 -0.2794)
			(stroke
				(width 0.1)
				(type default)
			)
			(layer "F.Fab")
		)
		(fp_line
			(start -0.12065 0.2794)
			(end -0.12065 0.3048)
			(stroke
				(width 0.1)
				(type default)
			)
			(layer "F.Fab")
		)
		(fp_line
			(start -0.12065 0.3048)
			(end -0.67945 0.3048)
			(stroke
				(width 0.1)
				(type default)
			)
			(layer "F.Fab")
		)
		(fp_line
			(start 0.120396 0.2794)
			(end -0.12065 0.2794)
			(stroke
				(width 0.1)
				(type default)
			)
			(layer "F.Fab")
		)
		(fp_line
			(start 0.120396 0.3048)
			(end 0.120396 0.2794)
			(stroke
				(width 0.1)
				(type default)
			)
			(layer "F.Fab")
		)
		(fp_line
			(start 0.12065 -0.3048)
			(end 0.67945 -0.3048)
			(stroke
				(width 0.1)
				(type default)
			)
			(layer "F.Fab")
		)
		(fp_line
			(start 0.12065 -0.2794)
			(end 0.12065 -0.3048)
			(stroke
				(width 0.1)
				(type default)
			)
			(layer "F.Fab")
		)
		(fp_line
			(start 0.67945 -0.3048)
			(end 0.67945 0.3048)
			(stroke
				(width 0.1)
				(type default)
			)
			(layer "F.Fab")
		)
		(fp_line
			(start 0.67945 0.3048)
			(end 0.120396 0.3048)
			(stroke
				(width 0.1)
				(type default)
			)
			(layer "F.Fab")
		)
		(pad "1" smd circle
			(at -0.40005 0)
			(size 0 0)
			(layers "F.Cu" "F.Mask" "F.Paste")
			(net "RST_PEX_NIC2_PERST_N")
		)
		(pad "2" smd circle
			(at 0.40005 0)
			(size 0 0)
			(layers "F.Cu" "F.Mask" "F.Paste")
			(net "RST_PEX_NIC2_PERST_R_N")
		)
	)
	(footprint ""
		(layer "F.Cu")
		(at 96.131888 -201.109326 90)
		(property "Reference" "R6622"
			(at 0 0 90)
			(layer "F.SilkS")
			(hide yes)
			(effects
				(font
					(size 1.27 1.27)
				)
			)
		)
		(property "Value" ""
			(at 0 0 90)
			(layer "F.Fab")
			(effects
				(font
					(size 1.27 1.27)
				)
			)
		)
		(duplicate_pad_numbers_are_jumpers no)
		(fp_line
			(start 0.7874 -0.4064)
			(end 0.7874 0.4064)
			(stroke
				(width 0.1524)
				(type default)
			)
			(layer "F.SilkS")
		)
		(fp_line
			(start -0.7874 -0.4064)
			(end 0.7874 -0.4064)
			(stroke
				(width 0.1524)
				(type default)
			)
			(layer "F.SilkS")
		)
		(fp_line
			(start 0.7874 0.4064)
			(end -0.7874 0.4064)
			(stroke
				(width 0.1524)
				(type default)
			)
			(layer "F.SilkS")
		)
		(fp_line
			(start -0.7874 0.4064)
			(end -0.7874 -0.4064)
			(stroke
				(width 0.1524)
				(type default)
			)
			(layer "F.SilkS")
		)
		(fp_line
			(start -0.12065 -0.305054)
			(end -0.12065 -0.2794)
			(stroke
				(width 0.1)
				(type default)
			)
			(layer "F.Fab")
		)
		(fp_line
			(start -0.67945 -0.305054)
			(end -0.12065 -0.305054)
			(stroke
				(width 0.1)
				(type default)
			)
			(layer "F.Fab")
		)
		(fp_line
			(start 0.67945 -0.3048)
			(end 0.67945 0.3048)
			(stroke
				(width 0.1)
				(type default)
			)
			(layer "F.Fab")
		)
		(fp_line
			(start 0.12065 -0.3048)
			(end 0.67945 -0.3048)
			(stroke
				(width 0.1)
				(type default)
			)
			(layer "F.Fab")
		)
		(fp_line
			(start 0.12065 -0.2794)
			(end 0.12065 -0.3048)
			(stroke
				(width 0.1)
				(type default)
			)
			(layer "F.Fab")
		)
		(fp_line
			(start -0.12065 -0.2794)
			(end 0.12065 -0.2794)
			(stroke
				(width 0.1)
				(type default)
			)
			(layer "F.Fab")
		)
		(fp_line
			(start 0.120396 0.2794)
			(end -0.12065 0.2794)
			(stroke
				(width 0.1)
				(type default)
			)
			(layer "F.Fab")
		)
		(fp_line
			(start -0.12065 0.2794)
			(end -0.12065 0.3048)
			(stroke
				(width 0.1)
				(type default)
			)
			(layer "F.Fab")
		)
		(fp_line
			(start 0.67945 0.3048)
			(end 0.120396 0.3048)
			(stroke
				(width 0.1)
				(type default)
			)
			(layer "F.Fab")
		)
		(fp_line
			(start 0.120396 0.3048)
			(end 0.120396 0.2794)
			(stroke
				(width 0.1)
				(type default)
			)
			(layer "F.Fab")
		)
		(fp_line
			(start -0.12065 0.3048)
			(end -0.67945 0.3048)
			(stroke
				(width 0.1)
				(type default)
			)
			(layer "F.Fab")
		)
		(fp_line
			(start -0.67945 0.3048)
			(end -0.67945 -0.305054)
			(stroke
				(width 0.1)
				(type default)
			)
			(layer "F.Fab")
		)
		(pad "1" smd circle
			(at -0.40005 0 90)
			(size 0 0)
			(layers "F.Cu" "F.Mask" "F.Paste")
			(net "RST_CP2108_CLI_R_N")
		)
		(pad "2" smd circle
			(at 0.40005 0 90)
			(size 0 0)
			(layers "F.Cu" "F.Mask" "F.Paste")
			(net "RST_FT4232_R_N")
		)
	)
	(footprint ""
		(layer "F.Cu")
		(at 265.51509 -20.72513)
		(property "Reference" "H112"
			(at 1.628394 -2.603754 0)
			(unlocked yes)
			(layer "B.SilkS")
			(effects
				(font
					(size 0.7874 0.5842)
					(thickness 0.1524)
				)
				(justify left mirror)
			)
		)
		(property "Value" ""
			(at 0 0 0)
			(layer "F.Fab")
			(effects
				(font
					(size 1.27 1.27)
				)
			)
		)
		(duplicate_pad_numbers_are_jumpers no)
		(pad "1" thru_hole rect
			(at 0 0)
			(size 4.2164 5.0038)
			(drill 2.0066
				(offset 0.099822 0)
			)
			(layers "*.Cu" "*.Mask")
			(remove_unused_layers no)
			(net "Net_8551")
			(clearance -0.8509)
			(padstack
				(mode front_inner_back)
				(layer "Inner"
					(shape circle)
					(size 4.0132 4.0132)
					(clearance -0.7493)
				)
				(layer "B.Cu"
					(shape circle)
					(size 4.0132 4.0132)
					(clearance -0.7493)
				)
			)
		)
	)
	(footprint ""
		(layer "F.Cu")
		(at 227.678234 -273.05762 90)
		(property "Reference" "C4280"
			(at 0 0 90)
			(layer "F.SilkS")
			(hide yes)
			(effects
				(font
					(size 1.27 1.27)
				)
			)
		)
		(property "Value" ""
			(at 0 0 90)
			(layer "F.Fab")
			(effects
				(font
					(size 1.27 1.27)
				)
			)
		)
		(duplicate_pad_numbers_are_jumpers no)
		(fp_line
			(start 0.299974 -0.150114)
			(end 0.299974 0.150114)
			(stroke
				(width 0.1)
				(type default)
			)
			(layer "F.Fab")
		)
		(fp_line
			(start -0.299974 -0.150114)
			(end 0.299974 -0.150114)
			(stroke
				(width 0.1)
				(type default)
			)
			(layer "F.Fab")
		)
		(fp_line
			(start 0.299974 0.150114)
			(end -0.299974 0.150114)
			(stroke
				(width 0.1)
				(type default)
			)
			(layer "F.Fab")
		)
		(fp_line
			(start -0.299974 0.150114)
			(end -0.299974 -0.150114)
			(stroke
				(width 0.1)
				(type default)
			)
			(layer "F.Fab")
		)
		(pad "1" smd rect
			(at -0.2667 0 90)
			(size 0.3048 0.381)
			(layers "F.Cu" "F.Mask" "F.Paste")
			(net "P1V25_SERDES_VDDPLL_PEX1")
		)
		(pad "2" smd rect
			(at 0.2667 0 90)
			(size 0.3048 0.381)
			(layers "F.Cu" "F.Mask" "F.Paste")
			(net "GND")
		)
	)
	(footprint ""
		(layer "F.Cu")
		(at 93.087444 -96.811592 90)
		(property "Reference" "R699"
			(at 0 0 90)
			(layer "F.SilkS")
			(hide yes)
			(effects
				(font
					(size 1.27 1.27)
				)
			)
		)
		(property "Value" ""
			(at 0 0 90)
			(layer "F.Fab")
			(effects
				(font
					(size 1.27 1.27)
				)
			)
		)
		(duplicate_pad_numbers_are_jumpers no)
		(fp_line
			(start 0.7874 -0.4064)
			(end 0.7874 0.4064)
			(stroke
				(width 0.1524)
				(type default)
			)
			(layer "F.SilkS")
		)
		(fp_line
			(start -0.7874 -0.4064)
			(end 0.7874 -0.4064)
			(stroke
				(width 0.1524)
				(type default)
			)
			(layer "F.SilkS")
		)
		(fp_line
			(start 0.7874 0.4064)
			(end -0.7874 0.4064)
			(stroke
				(width 0.1524)
				(type default)
			)
			(layer "F.SilkS")
		)
		(fp_line
			(start -0.7874 0.4064)
			(end -0.7874 -0.4064)
			(stroke
				(width 0.1524)
				(type default)
			)
			(layer "F.SilkS")
		)
		(fp_line
			(start -0.12065 -0.305054)
			(end -0.12065 -0.2794)
			(stroke
				(width 0.1)
				(type default)
			)
			(layer "F.Fab")
		)
		(fp_line
			(start -0.67945 -0.305054)
			(end -0.12065 -0.305054)
			(stroke
				(width 0.1)
				(type default)
			)
			(layer "F.Fab")
		)
		(fp_line
			(start 0.67945 -0.3048)
			(end 0.67945 0.3048)
			(stroke
				(width 0.1)
				(type default)
			)
			(layer "F.Fab")
		)
		(fp_line
			(start 0.12065 -0.3048)
			(end 0.67945 -0.3048)
			(stroke
				(width 0.1)
				(type default)
			)
			(layer "F.Fab")
		)
		(fp_line
			(start 0.12065 -0.2794)
			(end 0.12065 -0.3048)
			(stroke
				(width 0.1)
				(type default)
			)
			(layer "F.Fab")
		)
		(fp_line
			(start -0.12065 -0.2794)
			(end 0.12065 -0.2794)
			(stroke
				(width 0.1)
				(type default)
			)
			(layer "F.Fab")
		)
		(fp_line
			(start 0.120396 0.2794)
			(end -0.12065 0.2794)
			(stroke
				(width 0.1)
				(type default)
			)
			(layer "F.Fab")
		)
		(fp_line
			(start -0.12065 0.2794)
			(end -0.12065 0.3048)
			(stroke
				(width 0.1)
				(type default)
			)
			(layer "F.Fab")
		)
		(fp_line
			(start 0.67945 0.3048)
			(end 0.120396 0.3048)
			(stroke
				(width 0.1)
				(type default)
			)
			(layer "F.Fab")
		)
		(fp_line
			(start 0.120396 0.3048)
			(end 0.120396 0.2794)
			(stroke
				(width 0.1)
				(type default)
			)
			(layer "F.Fab")
		)
		(fp_line
			(start -0.12065 0.3048)
			(end -0.67945 0.3048)
			(stroke
				(width 0.1)
				(type default)
			)
			(layer "F.Fab")
		)
		(fp_line
			(start -0.67945 0.3048)
			(end -0.67945 -0.305054)
			(stroke
				(width 0.1)
				(type default)
			)
			(layer "F.Fab")
		)
		(pad "1" smd circle
			(at -0.40005 0 90)
			(size 0 0)
			(layers "F.Cu" "F.Mask" "F.Paste")
			(net "SMB_BIC_I2C6_MUX_NIC_ADC_R_SDA")
		)
		(pad "2" smd circle
			(at 0.40005 0 90)
			(size 0 0)
			(layers "F.Cu" "F.Mask" "F.Paste")
			(net "SMB_NIC1_ADC_SDA")
		)
	)
	(footprint ""
		(layer "F.Cu")
		(at 269.204694 -141.87297 180)
		(property "Reference" "R235"
			(at 0 0 180)
			(layer "F.SilkS")
			(hide yes)
			(effects
				(font
					(size 1.27 1.27)
				)
			)
		)
		(property "Value" ""
			(at 0 0 180)
			(layer "F.Fab")
			(effects
				(font
					(size 1.27 1.27)
				)
			)
		)
		(duplicate_pad_numbers_are_jumpers no)
		(fp_line
			(start 0.7874 0.4064)
			(end -0.7874 0.4064)
			(stroke
				(width 0.1524)
				(type default)
			)
			(layer "F.SilkS")
		)
		(fp_line
			(start 0.7874 -0.4064)
			(end 0.7874 0.4064)
			(stroke
				(width 0.1524)
				(type default)
			)
			(layer "F.SilkS")
		)
		(fp_line
			(start -0.7874 0.4064)
			(end -0.7874 -0.4064)
			(stroke
				(width 0.1524)
				(type default)
			)
			(layer "F.SilkS")
		)
		(fp_line
			(start -0.7874 -0.4064)
			(end 0.7874 -0.4064)
			(stroke
				(width 0.1524)
				(type default)
			)
			(layer "F.SilkS")
		)
		(fp_line
			(start 0.67945 0.3048)
			(end 0.120396 0.3048)
			(stroke
				(width 0.1)
				(type default)
			)
			(layer "F.Fab")
		)
		(fp_line
			(start 0.67945 -0.3048)
			(end 0.67945 0.3048)
			(stroke
				(width 0.1)
				(type default)
			)
			(layer "F.Fab")
		)
		(fp_line
			(start 0.12065 -0.2794)
			(end 0.12065 -0.3048)
			(stroke
				(width 0.1)
				(type default)
			)
			(layer "F.Fab")
		)
		(fp_line
			(start 0.12065 -0.3048)
			(end 0.67945 -0.3048)
			(stroke
				(width 0.1)
				(type default)
			)
			(layer "F.Fab")
		)
		(fp_line
			(start 0.120396 0.3048)
			(end 0.120396 0.2794)
			(stroke
				(width 0.1)
				(type default)
			)
			(layer "F.Fab")
		)
		(fp_line
			(start 0.120396 0.2794)
			(end -0.12065 0.2794)
			(stroke
				(width 0.1)
				(type default)
			)
			(layer "F.Fab")
		)
		(fp_line
			(start -0.12065 0.3048)
			(end -0.67945 0.3048)
			(stroke
				(width 0.1)
				(type default)
			)
			(layer "F.Fab")
		)
		(fp_line
			(start -0.12065 0.2794)
			(end -0.12065 0.3048)
			(stroke
				(width 0.1)
				(type default)
			)
			(layer "F.Fab")
		)
		(fp_line
			(start -0.12065 -0.2794)
			(end 0.12065 -0.2794)
			(stroke
				(width 0.1)
				(type default)
			)
			(layer "F.Fab")
		)
		(fp_line
			(start -0.12065 -0.305054)
			(end -0.12065 -0.2794)
			(stroke
				(width 0.1)
				(type default)
			)
			(layer "F.Fab")
		)
		(fp_line
			(start -0.67945 0.3048)
			(end -0.67945 -0.305054)
			(stroke
				(width 0.1)
				(type default)
			)
			(layer "F.Fab")
		)
		(fp_line
			(start -0.67945 -0.305054)
			(end -0.12065 -0.305054)
			(stroke
				(width 0.1)
				(type default)
			)
			(layer "F.Fab")
		)
		(pad "1" smd circle
			(at -0.40005 0 180)
			(size 0 0)
			(layers "F.Cu" "F.Mask" "F.Paste")
			(net "NIC4_BIF1_N")
		)
		(pad "2" smd circle
			(at 0.40005 0 180)
			(size 0 0)
			(layers "F.Cu" "F.Mask" "F.Paste")
			(net "P3V3_AUX")
		)
	)
)
